# BASEBOARD_FAB2 (Tioga Pass) — schematic netlist excerpt (pin names and nets, part order shuffled) for the footprints in the layout excerpt that follows; sources: Cadence DE-HDL packaged netlist, KiCad conversion of Wiwynn_Tioga_Pass_MB.brd

J1G3  SCONN288_H44441004  SCONN  pkg PIP  page 81
  \12v\(1)  = P12V_NVDIMM_GHJ
  VSS(93)  = GND
  DQ(4)  = M_J_DQ<5>
  VSS(92)  = GND
  DQ(0)  = M_J_DQ<1>
  VSS(91)  = GND
  DQS9P  = M_J_DQS_DP<9>
  DQS9N  = M_J_DQS_DN<9>
  VSS(90)  = GND
  DQ(6)  = M_J_DQ<7>
  VSS(89)  = GND
  DQ(2)  = M_J_DQ<3>
  VSS(88)  = GND
  DQ(12)  = M_J_DQ<13>
  VSS(87)  = GND
  DQ(8)  = M_J_DQ<9>
  VSS(86)  = GND
  DQS10P  = M_J_DQS_DP<10>
  DQS10N  = M_J_DQS_DN<10>
  VSS(85)  = GND
  DQ(14)  = M_J_DQ<15>
  VSS(84)  = GND
  DQ(10)  = M_J_DQ<11>
  VSS(83)  = GND
  DQ(20)  = M_J_DQ<21>
  VSS(82)  = GND
  DQ(16)  = M_J_DQ<17>
  VSS(81)  = GND
  DQS11P  = M_J_DQS_DP<11>
  DQS11N  = M_J_DQS_DN<11>
  VSS(80)  = GND
  DQ(22)  = M_J_DQ<23>
  VSS(79)  = GND
  DQ(18)  = M_J_DQ<19>
  VSS(78)  = GND
  DQ(28)  = M_J_DQ<29>
  VSS(77)  = GND
  DQ(24)  = M_J_DQ<25>
  VSS(76)  = GND
  DQS12P  = M_J_DQS_DP<12>
  DQS12N  = M_J_DQS_DN<12>
  VSS(75)  = GND
  DQ(30)  = M_J_DQ<31>
  VSS(74)  = GND
  DQ(26)  = M_J_DQ<27>
  VSS(73)  = GND
  CB(4)  = M_J_ECC<5>
  VSS(72)  = GND
  CB(0)  = M_J_ECC<1>
  VSS(71)  = GND
  DQS17P  = M_J_DQS_DP<17>
  DQS17N  = M_J_DQS_DN<17>
  VSS(70)  = GND
  CB(6)  = M_J_ECC<7>
  VSS(69)  = GND
  CB(2)  = M_J_ECC<3>
  VSS(68)  = GND
  RESET_N  = M_GHJ_RST_N
  VDD(25)  = PVDDQ_GHJ
  CKE(0)  = M_J_CKE<0>
  VDD(24)  = PVDDQ_GHJ
  ACT_N  = M_J_ACT_N
  BG(0)  = M_J_BG<0>
  VDD(23)  = PVDDQ_GHJ
  A12  = M_J_MA<12>
  A9  = M_J_MA<9>
  VDD(22)  = PVDDQ_GHJ
  A8  = M_J_MA<8>
  A6  = M_J_MA<6>
  VDD(21)  = PVDDQ_GHJ
  A3  = M_J_MA<3>
  A1  = M_J_MA<1>
  VDD(20)  = PVDDQ_GHJ
  CK0P  = M_J_CLK_DP<0>
  CK0N  = M_J_CLK_DN<0>
  VDD(19)  = PVDDQ_GHJ
  VTT(1)  = PVTT_GHJ
  EVENT_N  = FM_DIMM_EVENT_COD_N
  A0  = M_J_MA<0>
  VDD(18)  = PVDDQ_GHJ
  BA(0)  = M_J_BA<0>
  A16_RAS_N  = M_J_MA<16>
  VDD(17)  = PVDDQ_GHJ
  S0_N  = M_J_CS_N<0>
  VDD(16)  = PVDDQ_GHJ
  A15_CAS_N  = M_J_MA<15>
  ODT(0)  = M_J_ODT<0>
  VDD(15)  = PVDDQ_GHJ
  S1_N  = M_J_CS_N<1>
  VDD(14)  = PVDDQ_GHJ
  ODT(1)  = M_J_ODT<1>
  VDD(13)  = PVDDQ_GHJ
  S2_N_C(0)  = M_J_CS_N<2>
  VSS(67)  = GND
  DQ(36)  = M_J_DQ<37>
  VSS(66)  = GND
  DQ(32)  = M_J_DQ<33>
  VSS(65)  = GND
  DQS13P  = M_J_DQS_DP<13>
  DQS13N  = M_J_DQS_DN<13>
  VSS(64)  = GND
  DQ(38)  = M_J_DQ<39>
  VSS(63)  = GND
  DQ(34)  = M_J_DQ<35>
  VSS(62)  = GND
  DQ(44)  = M_J_DQ<45>
  VSS(61)  = GND
  DQ(40)  = M_J_DQ<41>
  VSS(60)  = GND
  DQS14P  = M_J_DQS_DP<14>
  DQS14N  = M_J_DQS_DN<14>
  VSS(59)  = GND
  DQ(46)  = M_J_DQ<47>
  VSS(58)  = GND
  DQ(42)  = M_J_DQ<43>
  VSS(57)  = GND
  DQ(52)  = M_J_DQ<53>
  VSS(56)  = GND
  DQ(48)  = M_J_DQ<49>
  VSS(55)  = GND
  DQS15P  = M_J_DQS_DP<15>
  DQS15N  = M_J_DQS_DN<15>
  VSS(54)  = GND
  DQ(54)  = M_J_DQ<55>
  VSS(53)  = GND
  DQ(50)  = M_J_DQ<51>
  VSS(52)  = GND
  DQ(60)  = M_J_DQ<61>
  VSS(51)  = GND
  DQ(56)  = M_J_DQ<57>
  VSS(50)  = GND
  DQS16P  = M_J_DQS_DP<16>
  DQS16N  = M_J_DQS_DN<16>
  VSS(49)  = GND
  DQ(62)  = M_J_DQ<63>
  VSS(48)  = GND
  DQ(58)  = M_J_DQ<59>
  VSS(47)  = GND
  SA(0)  = GND
  SA(1)  = GND
  SCL  = SMB_DDR_GHJ_VPP_SCL
  VPP(4)  = PVPP_GHJ
  VPP(3)  = PVPP_GHJ
  RFU(2)  = TP_CH_J_DIMM_J0_RFU_2
  \12v\(0)  = P12V_NVDIMM_GHJ
  VREFCA  = M_J_VREF
  VSS(46)  = GND
  DQ(5)  = M_J_DQ<4>
  VSS(45)  = GND
  DQ(1)  = M_J_DQ<0>
  VSS(44)  = GND
  DQS0N  = M_J_DQS_DN<0>
  DQS0P  = M_J_DQS_DP<0>
  VSS(43)  = GND
  DQ(7)  = M_J_DQ<6>
  VSS(42)  = GND
  DQ(3)  = M_J_DQ<2>
  VSS(41)  = GND
  DQ(13)  = M_J_DQ<12>
  VSS(40)  = GND
  DQ(9)  = M_J_DQ<8>
  VSS(39)  = GND
  DQS1N  = M_J_DQS_DN<1>
  DQS1P  = M_J_DQS_DP<1>
  VSS(38)  = GND
  DQ(15)  = M_J_DQ<14>
  VSS(37)  = GND
  DQ(11)  = M_J_DQ<10>
  VSS(36)  = GND
  DQ(21)  = M_J_DQ<20>
  VSS(35)  = GND
  DQ(17)  = M_J_DQ<16>
  VSS(34)  = GND
  DQS2N  = M_J_DQS_DN<2>
  DQS2P  = M_J_DQS_DP<2>
  VSS(33)  = GND
  DQ(23)  = M_J_DQ<22>
  VSS(32)  = GND
  DQ(19)  = M_J_DQ<18>
  VSS(31)  = GND
  DQ(29)  = M_J_DQ<28>
  VSS(30)  = GND
  DQ(25)  = M_J_DQ<24>
  VSS(29)  = GND
  DQS3N  = M_J_DQS_DN<3>
  DQS3P  = M_J_DQS_DP<3>
  VSS(28)  = GND
  DQ(31)  = M_J_DQ<30>
  VSS(27)  = GND
  DQ(27)  = M_J_DQ<26>
  VSS(26)  = GND
  CB(5)  = M_J_ECC<4>
  VSS(25)  = GND
  CB(1)  = M_J_ECC<0>
  VSS(24)  = GND
  DQS8N  = M_J_DQS_DN<8>
  DQS8P  = M_J_DQS_DP<8>
  VSS(23)  = GND
  CB(7)  = M_J_ECC<6>
  VSS(22)  = GND
  CB(3)  = M_J_ECC<2>
  VSS(21)  = GND
  CKE(1)  = M_J_CKE<1>
  VDD(12)  = PVDDQ_GHJ
  RFU(0)  = TP_CH_J_DIMM_J0_RFU_0
  VDD(11)  = PVDDQ_GHJ
  BG(1)  = M_J_BG<1>
  ALERT_N  = M_J_ALERT_N
  VDD(10)  = PVDDQ_GHJ
  A11  = M_J_MA<11>
  A7  = M_J_MA<7>
  VDD(9)  = PVDDQ_GHJ
  A5  = M_J_MA<5>
  A4  = M_J_MA<4>
  VDD(8)  = PVDDQ_GHJ
  A2  = M_J_MA<2>
  VDD(7)  = PVDDQ_GHJ
  CK1P  = M_J_CLK_DP<1>
  CK1N  = M_J_CLK_DN<1>
  VDD(6)  = PVDDQ_GHJ
  VTT(0)  = PVTT_GHJ
  PAR  = M_J_PAR
  VDD(5)  = PVDDQ_GHJ
  BA(1)  = M_J_BA<1>
  A10  = M_J_MA<10>
  VDD(4)  = PVDDQ_GHJ
  RFU(1)  = TP_CH_J_DIMM_J0_RFU_1
  A14_WE_N  = M_J_MA<14>
  VDD(3)  = PVDDQ_GHJ
  SAVE_N_NC  = FM_ADR_COMPLETE_GHJ_N
  VDD(2)  = PVDDQ_GHJ
  A13  = M_J_MA<13>
  VDD(1)  = PVDDQ_GHJ
  A17  = M_J_MA<17>
  C(2)  = M_J_C<2>
  VDD(0)  = PVDDQ_GHJ
  S3_N_C(1)  = M_J_CS_N<3>
  SA(2)  = PVPP_GHJ
  VSS(20)  = GND
  DQ(37)  = M_J_DQ<36>
  VSS(19)  = GND
  DQ(33)  = M_J_DQ<32>
  VSS(18)  = GND
  DQS4N  = M_J_DQS_DN<4>
  DQS4P  = M_J_DQS_DP<4>
  VSS(17)  = GND
  DQ(39)  = M_J_DQ<38>
  VSS(16)  = GND
  DQ(35)  = M_J_DQ<34>
  VSS(15)  = GND
  DQ(45)  = M_J_DQ<44>
  VSS(14)  = GND
  DQ(41)  = M_J_DQ<40>
  VSS(13)  = GND
  DQS5N  = M_J_DQS_DN<5>
  DQS5P  = M_J_DQS_DP<5>
  VSS(12)  = GND
  DQ(47)  = M_J_DQ<46>
  VSS(11)  = GND
  DQ(43)  = M_J_DQ<42>
  VSS(10)  = GND
  DQ(53)  = M_J_DQ<52>
  VSS(9)  = GND
  DQ(49)  = M_J_DQ<48>
  VSS(8)  = GND
  DQS6N  = M_J_DQS_DN<6>
  DQS6P  = M_J_DQS_DP<6>
  VSS(7)  = GND
  DQ(55)  = M_J_DQ<54>
  VSS(6)  = GND
  DQ(51)  = M_J_DQ<50>
  VSS(5)  = GND
  DQ(61)  = M_J_DQ<60>
  VSS(4)  = GND
  DQ(57)  = M_J_DQ<56>
  VSS(3)  = GND
  DQS7N  = M_J_DQS_DN<7>
  DQS7P  = M_J_DQS_DP<7>
  VSS(2)  = GND
  DQ(63)  = M_J_DQ<62>
  VSS(1)  = GND
  DQ(59)  = M_J_DQ<58>
  VSS(0)  = GND
  VDDSPD  = PVPP_GHJ
  SDA  = SMB_DDR_GHJ_VPP_SDA
  VPP(1)  = PVPP_GHJ
  VPP(0)  = PVPP_GHJ
  VPP(2)  = PVPP_GHJ

(kicad_pcb
	(version 20260206)
	(generator "pcbnew")
	(generator_version "10.0")
	(general
		(thickness 1.6)
		(legacy_teardrops no)
	)
	(paper "A4")
	(title_block
		(title "Wiwynn_Tioga_Pass_MB.brd")
		(comment 1 "Tioga Pass / footprint 437 of 4770 (J1G3), pads 203-250 of 291")
	)
	(layers
		(0 "F.Cu" signal "TOP")
		(4 "In1.Cu" signal "L2GND")
		(6 "In2.Cu" signal "L3")
		(8 "In3.Cu" signal "L4GND")
		(10 "In4.Cu" signal "L5")
		(12 "In5.Cu" signal "L6GND")
		(14 "In6.Cu" signal "L7VCC")
		(16 "In7.Cu" signal "L8VCC")
		(18 "In8.Cu" signal "L9GND")
		(20 "In9.Cu" signal "L10")
		(22 "In10.Cu" signal "L11GND")
		(24 "In11.Cu" signal "L12")
		(26 "In12.Cu" signal "L13GND")
		(2 "B.Cu" signal "BOTTOM")
		(9 "F.Adhes" user "F.Adhesive")
		(11 "B.Adhes" user "B.Adhesive")
		(13 "F.Paste" user "Package Geometry/Pastemask Top")
		(15 "B.Paste" user "Package Geometry/Pastemask Bottom")
		(5 "F.SilkS" user "Ref Des/Silkscreen Top")
		(7 "B.SilkS" user "Ref Des/Silkscreen Bottom")
		(1 "F.Mask" user "Board Geometry/Soldermask Top")
		(3 "B.Mask" user "Board Geometry/Soldermask Bottom")
		(17 "Dwgs.User" user "User.Drawings")
		(19 "Cmts.User" user "User.Comments")
		(21 "Eco1.User" user "User.Eco1")
		(23 "Eco2.User" user "User.Eco2")
		(25 "Edge.Cuts" user "Board Geometry/Outline")
		(27 "Margin" user)
		(31 "F.CrtYd" user "Package Geometry/Place Bound Top")
		(29 "B.CrtYd" user "Package Geometry/Place Bound Bottom")
		(35 "F.Fab" user "Ref Des/Assembly Top")
		(33 "B.Fab" user "Ref Des/Assembly Bottom")
	)
	(footprint ""
		(layer "F.Cu")
		(at 29.699458 3.778758 90)
		(property "Reference" "J1G3"
			(at 7.054088 34.562542 0)
			(unlocked yes)
			(layer "F.SilkS")
			(effects
				(font
					(size 0.7874 0.5842)
					(thickness 0.1524)
				)
				(justify left)
			)
		)
		(property "Value" ""
			(at 0 0 90)
			(layer "F.Fab")
			(effects
				(font
					(size 1.27 1.27)
				)
			)
		)
		(duplicate_pad_numbers_are_jumpers no)
		(pad "200" smd rect
			(at 4.59994 46.74997 90)
			(size 1.8034 0.508)
			(layers "F.Cu" "F.Mask" "F.Paste")
			(net "GND")
		)
		(pad "201" smd rect
			(at 4.59994 47.600108 90)
			(size 1.8034 0.508)
			(layers "F.Cu" "F.Mask" "F.Paste")
			(net "M_J_ECC<2>")
		)
		(pad "202" smd rect
			(at 4.59994 48.449992 90)
			(size 1.8034 0.508)
			(layers "F.Cu" "F.Mask" "F.Paste")
			(net "GND")
		)
		(pad "203" smd rect
			(at 4.59994 49.299876 90)
			(size 1.8034 0.508)
			(layers "F.Cu" "F.Mask" "F.Paste")
			(net "M_J_CKE<1>")
		)
		(pad "204" smd rect
			(at 4.59994 50.150014 90)
			(size 1.8034 0.508)
			(layers "F.Cu" "F.Mask" "F.Paste")
			(net "PVDDQ_GHJ")
		)
		(pad "205" smd rect
			(at 4.59994 50.999898 90)
			(size 1.8034 0.508)
			(layers "F.Cu" "F.Mask" "F.Paste")
			(net "TP_CH_J_DIMM_J0_RFU_0")
		)
		(pad "206" smd rect
			(at 4.59994 51.850036 90)
			(size 1.8034 0.508)
			(layers "F.Cu" "F.Mask" "F.Paste")
			(net "PVDDQ_GHJ")
		)
		(pad "207" smd rect
			(at 4.59994 52.69992 90)
			(size 1.8034 0.508)
			(layers "F.Cu" "F.Mask" "F.Paste")
			(net "M_J_BG<1>")
		)
		(pad "208" smd rect
			(at 4.59994 53.550058 90)
			(size 1.8034 0.508)
			(layers "F.Cu" "F.Mask" "F.Paste")
			(net "M_J_ALERT_N")
		)
		(pad "209" smd rect
			(at 4.59994 54.399942 90)
			(size 1.8034 0.508)
			(layers "F.Cu" "F.Mask" "F.Paste")
			(net "PVDDQ_GHJ")
		)
		(pad "210" smd rect
			(at 4.59994 55.25008 90)
			(size 1.8034 0.508)
			(layers "F.Cu" "F.Mask" "F.Paste")
			(net "M_J_MA<11>")
		)
		(pad "211" smd rect
			(at 4.59994 56.099964 90)
			(size 1.8034 0.508)
			(layers "F.Cu" "F.Mask" "F.Paste")
			(net "M_J_MA<7>")
		)
		(pad "212" smd rect
			(at 4.59994 56.950102 90)
			(size 1.8034 0.508)
			(layers "F.Cu" "F.Mask" "F.Paste")
			(net "PVDDQ_GHJ")
		)
		(pad "213" smd rect
			(at 4.59994 57.799986 90)
			(size 1.8034 0.508)
			(layers "F.Cu" "F.Mask" "F.Paste")
			(net "M_J_MA<5>")
		)
		(pad "214" smd rect
			(at 4.59994 58.650124 90)
			(size 1.8034 0.508)
			(layers "F.Cu" "F.Mask" "F.Paste")
			(net "M_J_MA<4>")
		)
		(pad "215" smd rect
			(at 4.59994 59.500008 90)
			(size 1.8034 0.508)
			(layers "F.Cu" "F.Mask" "F.Paste")
			(net "PVDDQ_GHJ")
		)
		(pad "216" smd rect
			(at 4.59994 60.349892 90)
			(size 1.8034 0.508)
			(layers "F.Cu" "F.Mask" "F.Paste")
			(net "M_J_MA<2>")
		)
		(pad "217" smd rect
			(at 4.59994 61.20003 90)
			(size 1.8034 0.508)
			(layers "F.Cu" "F.Mask" "F.Paste")
			(net "PVDDQ_GHJ")
		)
		(pad "218" smd rect
			(at 4.59994 62.049914 90)
			(size 1.8034 0.508)
			(layers "F.Cu" "F.Mask" "F.Paste")
			(net "M_J_CLK_DP<1>")
		)
		(pad "219" smd rect
			(at 4.59994 62.900052 90)
			(size 1.8034 0.508)
			(layers "F.Cu" "F.Mask" "F.Paste")
			(net "M_J_CLK_DN<1>")
		)
		(pad "220" smd rect
			(at 4.59994 63.749936 90)
			(size 1.8034 0.508)
			(layers "F.Cu" "F.Mask" "F.Paste")
			(net "PVDDQ_GHJ")
		)
		(pad "221" smd rect
			(at 4.59994 64.600074 90)
			(size 1.8034 0.508)
			(layers "F.Cu" "F.Mask" "F.Paste")
			(net "PVTT_GHJ")
		)
		(pad "222" smd rect
			(at 4.59994 70.550024 90)
			(size 1.8034 0.508)
			(layers "F.Cu" "F.Mask" "F.Paste")
			(net "M_J_PAR")
		)
		(pad "223" smd rect
			(at 4.59994 71.399908 90)
			(size 1.8034 0.508)
			(layers "F.Cu" "F.Mask" "F.Paste")
			(net "PVDDQ_GHJ")
		)
		(pad "224" smd rect
			(at 4.59994 72.250046 90)
			(size 1.8034 0.508)
			(layers "F.Cu" "F.Mask" "F.Paste")
			(net "M_J_BA<1>")
		)
		(pad "225" smd rect
			(at 4.59994 73.09993 90)
			(size 1.8034 0.508)
			(layers "F.Cu" "F.Mask" "F.Paste")
			(net "M_J_MA<10>")
		)
		(pad "226" smd rect
			(at 4.59994 73.950068 90)
			(size 1.8034 0.508)
			(layers "F.Cu" "F.Mask" "F.Paste")
			(net "PVDDQ_GHJ")
		)
		(pad "227" smd rect
			(at 4.59994 74.799952 90)
			(size 1.8034 0.508)
			(layers "F.Cu" "F.Mask" "F.Paste")
			(net "TP_CH_J_DIMM_J0_RFU_1")
		)
		(pad "228" smd rect
			(at 4.59994 75.65009 90)
			(size 1.8034 0.508)
			(layers "F.Cu" "F.Mask" "F.Paste")
			(net "M_J_MA<14>")
		)
		(pad "229" smd rect
			(at 4.59994 76.499974 90)
			(size 1.8034 0.508)
			(layers "F.Cu" "F.Mask" "F.Paste")
			(net "PVDDQ_GHJ")
		)
		(pad "230" smd rect
			(at 4.59994 77.350112 90)
			(size 1.8034 0.508)
			(layers "F.Cu" "F.Mask" "F.Paste")
			(net "FM_ADR_COMPLETE_GHJ_N")
		)
		(pad "231" smd rect
			(at 4.59994 78.199996 90)
			(size 1.8034 0.508)
			(layers "F.Cu" "F.Mask" "F.Paste")
			(net "PVDDQ_GHJ")
		)
		(pad "232" smd rect
			(at 4.59994 79.04988 90)
			(size 1.8034 0.508)
			(layers "F.Cu" "F.Mask" "F.Paste")
			(net "M_J_MA<13>")
		)
		(pad "233" smd rect
			(at 4.59994 79.900018 90)
			(size 1.8034 0.508)
			(layers "F.Cu" "F.Mask" "F.Paste")
			(net "PVDDQ_GHJ")
		)
		(pad "234" smd rect
			(at 4.59994 80.749902 90)
			(size 1.8034 0.508)
			(layers "F.Cu" "F.Mask" "F.Paste")
			(net "M_J_MA<17>")
		)
		(pad "235" smd rect
			(at 4.59994 81.60004 90)
			(size 1.8034 0.508)
			(layers "F.Cu" "F.Mask" "F.Paste")
			(net "M_J_C<2>")
		)
		(pad "236" smd rect
			(at 4.59994 82.449924 90)
			(size 1.8034 0.508)
			(layers "F.Cu" "F.Mask" "F.Paste")
			(net "PVDDQ_GHJ")
		)
		(pad "237" smd rect
			(at 4.59994 83.300062 90)
			(size 1.8034 0.508)
			(layers "F.Cu" "F.Mask" "F.Paste")
			(net "M_J_CS_N<3>")
		)
		(pad "238" smd rect
			(at 4.59994 84.149946 90)
			(size 1.8034 0.508)
			(layers "F.Cu" "F.Mask" "F.Paste")
			(net "PVPP_GHJ")
		)
		(pad "239" smd rect
			(at 4.59994 85.000084 90)
			(size 1.8034 0.508)
			(layers "F.Cu" "F.Mask" "F.Paste")
			(net "GND")
		)
		(pad "240" smd rect
			(at 4.59994 85.849968 90)
			(size 1.8034 0.508)
			(layers "F.Cu" "F.Mask" "F.Paste")
			(net "M_J_DQ<36>")
		)
		(pad "241" smd rect
			(at 4.59994 86.700106 90)
			(size 1.8034 0.508)
			(layers "F.Cu" "F.Mask" "F.Paste")
			(net "GND")
		)
		(pad "242" smd rect
			(at 4.59994 87.54999 90)
			(size 1.8034 0.508)
			(layers "F.Cu" "F.Mask" "F.Paste")
			(net "M_J_DQ<32>")
		)
		(pad "243" smd rect
			(at 4.59994 88.399874 90)
			(size 1.8034 0.508)
			(layers "F.Cu" "F.Mask" "F.Paste")
			(net "GND")
		)
		(pad "244" smd rect
			(at 4.59994 89.250012 90)
			(size 1.8034 0.508)
			(layers "F.Cu" "F.Mask" "F.Paste")
			(net "M_J_DQS_DN<4>")
		)
		(pad "245" smd rect
			(at 4.59994 90.099896 90)
			(size 1.8034 0.508)
			(layers "F.Cu" "F.Mask" "F.Paste")
			(net "M_J_DQS_DP<4>")
		)
		(pad "246" smd rect
			(at 4.59994 90.950034 90)
			(size 1.8034 0.508)
			(layers "F.Cu" "F.Mask" "F.Paste")
			(net "GND")
		)
		(pad "247" smd rect
			(at 4.59994 91.799918 90)
			(size 1.8034 0.508)
			(layers "F.Cu" "F.Mask" "F.Paste")
			(net "M_J_DQ<38>")
		)
	)
)
